FILE_TYPE=LIBRARY_PARTS;
primitive 'TPS3808G18DBVR';
  pin
    '#RESET':
      PIN_NUMBER='(1)';
      OUTPUT_LOAD='(1.0,-1.0)';
    'GND':
      PIN_NUMBER='(2)';
      PINUSE='POWER';
      NO_LOAD_CHECK='Both';
      NO_IO_CHECK='Both';
      NO_ASSERT_CHECK='TRUE';
      NO_DIR_CHECK='TRUE';
      ALLOW_CONNECT='TRUE';
    '#MR':
      PIN_NUMBER='(3)';
      INPUT_LOAD='(-0.01,0.01)';
    'VDD':
      PIN_NUMBER='(6)';
      PINUSE='POWER';
      NO_LOAD_CHECK='Both';
      NO_IO_CHECK='Both';
      NO_ASSERT_CHECK='TRUE';
      NO_DIR_CHECK='TRUE';
      ALLOW_CONNECT='TRUE';
    'CT':
      PIN_NUMBER='(4)';
      INPUT_LOAD='(-0.01,0.01)';
    'SENSE':
      PIN_NUMBER='(5)';
      PINUSE='POWER';
      NO_LOAD_CHECK='Both';
      NO_IO_CHECK='Both';
      NO_ASSERT_CHECK='TRUE';
      NO_DIR_CHECK='TRUE';
      ALLOW_CONNECT='TRUE';
  end_pin;
  body
    PART_NAME='TPS3808G18DBVR';
    BODY_NAME='TPS3808G18DBVR';
    PHYS_DES_PREFIX='U';
    CLASS='IC';
  end_body;
end_primitive;

END.
